(kicad_pcb
	(version 20260206)
	(generator "pcbnew")
	(generator_version "10.0")
	(general
		(thickness 1.6)
		(legacy_teardrops no)
	)
	(paper "A4")
	(title_block
		(title "03242023_DA0F0TMBIJ0_F0T_Motherboard_J_brd_V01_OCP.brd")
		(comment 1 "Grand Teton / footprints 1359-1364 of 6105")
	)
	(layers
		(0 "F.Cu" signal "TOP")
		(4 "In1.Cu" signal "GND")
		(6 "In2.Cu" signal "IN1")
		(8 "In3.Cu" signal "GND1")
		(10 "In4.Cu" signal "IN2")
		(12 "In5.Cu" signal "GND2")
		(14 "In6.Cu" signal "IN3")
		(16 "In7.Cu" signal "GND3")
		(18 "In8.Cu" signal "VCC")
		(20 "In9.Cu" signal "VCC1")
		(22 "In10.Cu" signal "GND4")
		(24 "In11.Cu" signal "IN4")
		(26 "In12.Cu" signal "GND5")
		(28 "In13.Cu" signal "IN5")
		(30 "In14.Cu" signal "GND6")
		(32 "In15.Cu" signal "IN6")
		(34 "In16.Cu" signal "GND7")
		(2 "B.Cu" signal "BOTTOM")
		(9 "F.Adhes" user "F.Adhesive")
		(11 "B.Adhes" user "B.Adhesive")
		(13 "F.Paste" user "Package Geometry/Pastemask Top")
		(15 "B.Paste" user "Package Geometry/Pastemask Bottom")
		(5 "F.SilkS" user "Ref Des/Silkscreen Top")
		(7 "B.SilkS" user "Ref Des/Silkscreen Bottom")
		(1 "F.Mask" user "Board Geometry/Soldermask Top")
		(3 "B.Mask" user "Board Geometry/Soldermask Bottom")
		(17 "Dwgs.User" user "User.Drawings")
		(19 "Cmts.User" user "User.Comments")
		(21 "Eco1.User" user "User.Eco1")
		(23 "Eco2.User" user "User.Eco2")
		(25 "Edge.Cuts" user "Board Geometry/Outline")
		(27 "Margin" user)
		(31 "F.CrtYd" user "Package Geometry/Place Bound Top")
		(29 "B.CrtYd" user "Package Geometry/Place Bound Bottom")
		(35 "F.Fab" user "Ref Des/Assembly Top")
		(33 "B.Fab" user "Ref Des/Assembly Bottom")
	)
	(footprint ""
		(layer "F.Cu")
		(at 438.277 -96.357948 90)
		(property "Reference" "C2015"
			(at 0 0 90)
			(layer "F.SilkS")
			(hide yes)
			(effects
				(font
					(size 1.27 1.27)
				)
			)
		)
		(property "Value" ""
			(at 0 0 90)
			(layer "F.Fab")
			(effects
				(font
					(size 1.27 1.27)
				)
			)
		)
		(duplicate_pad_numbers_are_jumpers no)
		(fp_line
			(start 0.7874 -0.4064)
			(end 0.7874 0.4064)
			(stroke
				(width 0.1524)
				(type default)
			)
			(layer "F.SilkS")
		)
		(fp_line
			(start -0.7874 -0.4064)
			(end 0.7874 -0.4064)
			(stroke
				(width 0.1524)
				(type default)
			)
			(layer "F.SilkS")
		)
		(fp_line
			(start 0.7874 0.4064)
			(end -0.7874 0.4064)
			(stroke
				(width 0.1524)
				(type default)
			)
			(layer "F.SilkS")
		)
		(fp_line
			(start -0.7874 0.4064)
			(end -0.7874 -0.4064)
			(stroke
				(width 0.1524)
				(type default)
			)
			(layer "F.SilkS")
		)
		(fp_line
			(start -0.12065 -0.305054)
			(end -0.12065 -0.2794)
			(stroke
				(width 0.1)
				(type default)
			)
			(layer "F.Fab")
		)
		(fp_line
			(start -0.67945 -0.305054)
			(end -0.12065 -0.305054)
			(stroke
				(width 0.1)
				(type default)
			)
			(layer "F.Fab")
		)
		(fp_line
			(start 0.67945 -0.3048)
			(end 0.67945 0.3048)
			(stroke
				(width 0.1)
				(type default)
			)
			(layer "F.Fab")
		)
		(fp_line
			(start 0.12065 -0.3048)
			(end 0.67945 -0.3048)
			(stroke
				(width 0.1)
				(type default)
			)
			(layer "F.Fab")
		)
		(fp_line
			(start 0.12065 -0.2794)
			(end 0.12065 -0.3048)
			(stroke
				(width 0.1)
				(type default)
			)
			(layer "F.Fab")
		)
		(fp_line
			(start -0.12065 -0.2794)
			(end 0.12065 -0.2794)
			(stroke
				(width 0.1)
				(type default)
			)
			(layer "F.Fab")
		)
		(fp_line
			(start 0.120396 0.2794)
			(end -0.12065 0.2794)
			(stroke
				(width 0.1)
				(type default)
			)
			(layer "F.Fab")
		)
		(fp_line
			(start -0.12065 0.2794)
			(end -0.12065 0.3048)
			(stroke
				(width 0.1)
				(type default)
			)
			(layer "F.Fab")
		)
		(fp_line
			(start 0.67945 0.3048)
			(end 0.120396 0.3048)
			(stroke
				(width 0.1)
				(type default)
			)
			(layer "F.Fab")
		)
		(fp_line
			(start 0.120396 0.3048)
			(end 0.120396 0.2794)
			(stroke
				(width 0.1)
				(type default)
			)
			(layer "F.Fab")
		)
		(fp_line
			(start -0.12065 0.3048)
			(end -0.67945 0.3048)
			(stroke
				(width 0.1)
				(type default)
			)
			(layer "F.Fab")
		)
		(fp_line
			(start -0.67945 0.3048)
			(end -0.67945 -0.305054)
			(stroke
				(width 0.1)
				(type default)
			)
			(layer "F.Fab")
		)
		(pad "1" smd circle
			(at -0.40005 0 90)
			(size 0 0)
			(layers "F.Cu" "F.Mask" "F.Paste")
			(net "P3V3_AUX")
		)
		(pad "2" smd circle
			(at 0.40005 0 90)
			(size 0 0)
			(layers "F.Cu" "F.Mask" "F.Paste")
			(net "GND")
		)
	)
	(footprint ""
		(layer "F.Cu")
		(at 415.19729 -402.371052 -90)
		(property "Reference" "C962"
			(at 0 0 270)
			(layer "F.SilkS")
			(hide yes)
			(effects
				(font
					(size 1.27 1.27)
				)
			)
		)
		(property "Value" ""
			(at 0 0 270)
			(layer "F.Fab")
			(effects
				(font
					(size 1.27 1.27)
				)
			)
		)
		(duplicate_pad_numbers_are_jumpers no)
		(fp_line
			(start -0.299974 0.150114)
			(end -0.299974 -0.150114)
			(stroke
				(width 0.1)
				(type default)
			)
			(layer "F.Fab")
		)
		(fp_line
			(start 0.299974 0.150114)
			(end -0.299974 0.150114)
			(stroke
				(width 0.1)
				(type default)
			)
			(layer "F.Fab")
		)
		(fp_line
			(start -0.299974 -0.150114)
			(end 0.299974 -0.150114)
			(stroke
				(width 0.1)
				(type default)
			)
			(layer "F.Fab")
		)
		(fp_line
			(start 0.299974 -0.150114)
			(end 0.299974 0.150114)
			(stroke
				(width 0.1)
				(type default)
			)
			(layer "F.Fab")
		)
		(pad "1" smd rect
			(at -0.2667 0 270)
			(size 0.3048 0.381)
			(layers "F.Cu" "F.Mask" "F.Paste")
			(net "P5E_CPU0_PE2_TX_C_DN<1>")
		)
		(pad "2" smd rect
			(at 0.2667 0 270)
			(size 0.3048 0.381)
			(layers "F.Cu" "F.Mask" "F.Paste")
			(net "P5E_CPU0_PE2_TX_DN<1>")
		)
	)
	(footprint ""
		(layer "F.Cu")
		(at 339.298534 5.463794)
		(property "Reference" "J72"
			(at -4.245864 1.140206 90)
			(unlocked yes)
			(layer "F.SilkS")
			(effects
				(font
					(size 0.7874 0.5842)
					(thickness 0.1524)
				)
				(justify left)
			)
		)
		(property "Value" ""
			(at 0 0 0)
			(layer "F.Fab")
			(effects
				(font
					(size 1.27 1.27)
				)
			)
		)
		(duplicate_pad_numbers_are_jumpers no)
		(fp_line
			(start -1.2192 -2.1082)
			(end 1.2192 -2.1082)
			(stroke
				(width 0.1524)
				(type default)
			)
			(layer "F.SilkS")
		)
		(fp_line
			(start -1.2192 2.1082)
			(end -1.2192 -2.1082)
			(stroke
				(width 0.1524)
				(type default)
			)
			(layer "F.SilkS")
		)
		(fp_line
			(start 1.2192 -2.1082)
			(end 1.2192 2.1082)
			(stroke
				(width 0.1524)
				(type default)
			)
			(layer "F.SilkS")
		)
		(fp_line
			(start 1.2192 2.1082)
			(end -1.2192 2.1082)
			(stroke
				(width 0.1524)
				(type default)
			)
			(layer "F.SilkS")
		)
		(pad "" np_thru_hole circle
			(at -2.8829 -1.27 270)
			(size 1.0414 1.0414)
			(drill 1.0414)
			(layers "*.Cu" "*.Mask")
			(clearance 0.381)
			(thermal_gap 0.381)
		)
		(pad "" np_thru_hole circle
			(at -2.8829 1.27 270)
			(size 1.0414 1.0414)
			(drill 1.0414)
			(layers "*.Cu" "*.Mask")
			(clearance 0.381)
			(thermal_gap 0.381)
		)
		(pad "" np_thru_hole circle
			(at 3.4671 -1.27 270)
			(size 1.0414 1.0414)
			(drill 1.0414)
			(layers "*.Cu" "*.Mask")
			(clearance 0.381)
			(thermal_gap 0.381)
		)
		(pad "" np_thru_hole circle
			(at 3.4671 1.27 270)
			(size 1.0414 1.0414)
			(drill 1.0414)
			(layers "*.Cu" "*.Mask")
			(clearance 0.381)
			(thermal_gap 0.381)
		)
		(pad "1" smd rect
			(at 0.8255 -0.249936 270)
			(size 0.3048 0.508)
			(layers "F.Cu" "F.Mask" "F.Paste")
			(net "DELTA_L_85_5INCH_IN2_DN")
		)
		(pad "2" smd rect
			(at 0.8255 0.249936 270)
			(size 0.3048 0.508)
			(layers "F.Cu" "F.Mask" "F.Paste")
			(net "DELTA_L_85_5INCH_IN2_DP")
		)
		(pad "3" smd circle
			(at 0 0)
			(size 0 0)
			(layers "F.Cu" "F.Mask" "F.Paste")
			(net "DELTA_L_GND_1")
		)
		(zone
			(layer "F.Cu")
			(hatch none 0.5)
			(connect_pads
				(clearance 0)
			)
			(min_thickness 0.25)
			(keepout
				(tracks not_allowed)
				(vias allowed)
				(pads allowed)
				(copperpour not_allowed)
				(footprints allowed)
			)
			(placement
				(enabled no)
				(sheetname "")
			)
			(fill
				(thermal_gap 0.5)
				(thermal_bridge_width 0.5)
				(island_removal_mode 0)
			)
			(polygon
				(pts
					(xy 340.416134 4.915154) (xy 340.416134 5.010658) (xy 339.819234 5.010658) (xy 339.819234 5.417058)
					(xy 340.416134 5.417058) (xy 340.416134 5.51053) (xy 339.819234 5.51053) (xy 339.819234 5.91693)
					(xy 340.416134 5.91693) (xy 340.416134 6.012434) (xy 339.717634 6.012434) (xy 339.717634 4.915154)
				)
			)
		)
		(zone
			(layers "F.Cu" "B.Cu" "In1.Cu" "In2.Cu" "In3.Cu" "In4.Cu" "In5.Cu" "In6.Cu"
				"In7.Cu" "In8.Cu" "In9.Cu" "In10.Cu" "In11.Cu" "In12.Cu" "In13.Cu" "In14.Cu"
				"In15.Cu" "In16.Cu"
			)
			(hatch none 0.5)
			(connect_pads
				(clearance 0)
			)
			(min_thickness 0.25)
			(keepout
				(tracks not_allowed)
				(vias allowed)
				(pads allowed)
				(copperpour not_allowed)
				(footprints allowed)
			)
			(placement
				(enabled no)
				(sheetname "")
			)
			(fill
				(thermal_gap 0.5)
				(thermal_bridge_width 0.5)
				(island_removal_mode 0)
			)
			(polygon
				(pts
					(arc
						(start 337.342734 4.193794)
						(mid 335.488534 4.193794)
						(end 337.342734 4.193794)
					)
				)
			)
		)
		(zone
			(layers "F.Cu" "B.Cu" "In1.Cu" "In2.Cu" "In3.Cu" "In4.Cu" "In5.Cu" "In6.Cu"
				"In7.Cu" "In8.Cu" "In9.Cu" "In10.Cu" "In11.Cu" "In12.Cu" "In13.Cu" "In14.Cu"
				"In15.Cu" "In16.Cu"
			)
			(hatch none 0.5)
			(connect_pads
				(clearance 0)
			)
			(min_thickness 0.25)
			(keepout
				(tracks not_allowed)
				(vias allowed)
				(pads allowed)
				(copperpour not_allowed)
				(footprints allowed)
			)
			(placement
				(enabled no)
				(sheetname "")
			)
			(fill
				(thermal_gap 0.5)
				(thermal_bridge_width 0.5)
				(island_removal_mode 0)
			)
			(polygon
				(pts
					(arc
						(start 337.342734 6.733794)
						(mid 335.488534 6.733794)
						(end 337.342734 6.733794)
					)
				)
			)
		)
		(zone
			(layers "F.Cu" "B.Cu" "In1.Cu" "In2.Cu" "In3.Cu" "In4.Cu" "In5.Cu" "In6.Cu"
				"In7.Cu" "In8.Cu" "In9.Cu" "In10.Cu" "In11.Cu" "In12.Cu" "In13.Cu" "In14.Cu"
				"In15.Cu" "In16.Cu"
			)
			(hatch none 0.5)
			(connect_pads
				(clearance 0)
			)
			(min_thickness 0.25)
			(keepout
				(tracks not_allowed)
				(vias allowed)
				(pads allowed)
				(copperpour not_allowed)
				(footprints allowed)
			)
			(placement
				(enabled no)
				(sheetname "")
			)
			(fill
				(thermal_gap 0.5)
				(thermal_bridge_width 0.5)
				(island_removal_mode 0)
			)
			(polygon
				(pts
					(arc
						(start 343.692734 4.193794)
						(mid 341.838534 4.193794)
						(end 343.692734 4.193794)
					)
				)
			)
		)
		(zone
			(layers "F.Cu" "B.Cu" "In1.Cu" "In2.Cu" "In3.Cu" "In4.Cu" "In5.Cu" "In6.Cu"
				"In7.Cu" "In8.Cu" "In9.Cu" "In10.Cu" "In11.Cu" "In12.Cu" "In13.Cu" "In14.Cu"
				"In15.Cu" "In16.Cu"
			)
			(hatch none 0.5)
			(connect_pads
				(clearance 0)
			)
			(min_thickness 0.25)
			(keepout
				(tracks not_allowed)
				(vias allowed)
				(pads allowed)
				(copperpour not_allowed)
				(footprints allowed)
			)
			(placement
				(enabled no)
				(sheetname "")
			)
			(fill
				(thermal_gap 0.5)
				(thermal_bridge_width 0.5)
				(island_removal_mode 0)
			)
			(polygon
				(pts
					(arc
						(start 343.692734 6.733794)
						(mid 341.838534 6.733794)
						(end 343.692734 6.733794)
					)
				)
			)
		)
	)
	(footprint ""
		(layer "F.Cu")
		(at 320.185288 -402.371052 -90)
		(property "Reference" "C1569"
			(at 0 0 270)
			(layer "F.SilkS")
			(hide yes)
			(effects
				(font
					(size 1.27 1.27)
				)
			)
		)
		(property "Value" ""
			(at 0 0 270)
			(layer "F.Fab")
			(effects
				(font
					(size 1.27 1.27)
				)
			)
		)
		(duplicate_pad_numbers_are_jumpers no)
		(fp_line
			(start -0.299974 0.150114)
			(end -0.299974 -0.150114)
			(stroke
				(width 0.1)
				(type default)
			)
			(layer "F.Fab")
		)
		(fp_line
			(start 0.299974 0.150114)
			(end -0.299974 0.150114)
			(stroke
				(width 0.1)
				(type default)
			)
			(layer "F.Fab")
		)
		(fp_line
			(start -0.299974 -0.150114)
			(end 0.299974 -0.150114)
			(stroke
				(width 0.1)
				(type default)
			)
			(layer "F.Fab")
		)
		(fp_line
			(start 0.299974 -0.150114)
			(end 0.299974 0.150114)
			(stroke
				(width 0.1)
				(type default)
			)
			(layer "F.Fab")
		)
		(pad "1" smd rect
			(at -0.2667 0 270)
			(size 0.3048 0.381)
			(layers "F.Cu" "F.Mask" "F.Paste")
			(net "P5E_CPU0_PE4_TX_C_DP<5>")
		)
		(pad "2" smd rect
			(at 0.2667 0 270)
			(size 0.3048 0.381)
			(layers "F.Cu" "F.Mask" "F.Paste")
			(net "P5E_CPU0_PE4_TX_DP<5>")
		)
	)
	(footprint ""
		(layer "F.Cu")
		(at 127.635 -58.003948)
		(property "Reference" "C2348"
			(at 0 0 0)
			(layer "F.SilkS")
			(hide yes)
			(effects
				(font
					(size 1.27 1.27)
				)
			)
		)
		(property "Value" ""
			(at 0 0 0)
			(layer "F.Fab")
			(effects
				(font
					(size 1.27 1.27)
				)
			)
		)
		(duplicate_pad_numbers_are_jumpers no)
		(fp_line
			(start -0.7874 -0.4064)
			(end 0.7874 -0.4064)
			(stroke
				(width 0.1524)
				(type default)
			)
			(layer "F.SilkS")
		)
		(fp_line
			(start -0.7874 0.4064)
			(end -0.7874 -0.4064)
			(stroke
				(width 0.1524)
				(type default)
			)
			(layer "F.SilkS")
		)
		(fp_line
			(start 0.7874 -0.4064)
			(end 0.7874 0.4064)
			(stroke
				(width 0.1524)
				(type default)
			)
			(layer "F.SilkS")
		)
		(fp_line
			(start 0.7874 0.4064)
			(end -0.7874 0.4064)
			(stroke
				(width 0.1524)
				(type default)
			)
			(layer "F.SilkS")
		)
		(fp_line
			(start -0.67945 -0.305054)
			(end -0.12065 -0.305054)
			(stroke
				(width 0.1)
				(type default)
			)
			(layer "F.Fab")
		)
		(fp_line
			(start -0.67945 0.3048)
			(end -0.67945 -0.305054)
			(stroke
				(width 0.1)
				(type default)
			)
			(layer "F.Fab")
		)
		(fp_line
			(start -0.12065 -0.305054)
			(end -0.12065 -0.2794)
			(stroke
				(width 0.1)
				(type default)
			)
			(layer "F.Fab")
		)
		(fp_line
			(start -0.12065 -0.2794)
			(end 0.12065 -0.2794)
			(stroke
				(width 0.1)
				(type default)
			)
			(layer "F.Fab")
		)
		(fp_line
			(start -0.12065 0.2794)
			(end -0.12065 0.3048)
			(stroke
				(width 0.1)
				(type default)
			)
			(layer "F.Fab")
		)
		(fp_line
			(start -0.12065 0.3048)
			(end -0.67945 0.3048)
			(stroke
				(width 0.1)
				(type default)
			)
			(layer "F.Fab")
		)
		(fp_line
			(start 0.120396 0.2794)
			(end -0.12065 0.2794)
			(stroke
				(width 0.1)
				(type default)
			)
			(layer "F.Fab")
		)
		(fp_line
			(start 0.120396 0.3048)
			(end 0.120396 0.2794)
			(stroke
				(width 0.1)
				(type default)
			)
			(layer "F.Fab")
		)
		(fp_line
			(start 0.12065 -0.3048)
			(end 0.67945 -0.3048)
			(stroke
				(width 0.1)
				(type default)
			)
			(layer "F.Fab")
		)
		(fp_line
			(start 0.12065 -0.2794)
			(end 0.12065 -0.3048)
			(stroke
				(width 0.1)
				(type default)
			)
			(layer "F.Fab")
		)
		(fp_line
			(start 0.67945 -0.3048)
			(end 0.67945 0.3048)
			(stroke
				(width 0.1)
				(type default)
			)
			(layer "F.Fab")
		)
		(fp_line
			(start 0.67945 0.3048)
			(end 0.120396 0.3048)
			(stroke
				(width 0.1)
				(type default)
			)
			(layer "F.Fab")
		)
		(pad "1" smd circle
			(at -0.40005 0)
			(size 0 0)
			(layers "F.Cu" "F.Mask" "F.Paste")
			(net "P3V3_AUX")
		)
		(pad "2" smd circle
			(at 0.40005 0)
			(size 0 0)
			(layers "F.Cu" "F.Mask" "F.Paste")
			(net "GND")
		)
	)
	(footprint ""
		(layer "F.Cu")
		(at 136.00684 -38.049708)
		(property "Reference" "U246"
			(at -2.84988 1.82499 0)
			(unlocked yes)
			(layer "F.SilkS")
			(effects
				(font
					(size 0.7874 0.5842)
					(thickness 0.1524)
				)
			)
		)
		(property "Value" ""
			(at 0 0 0)
			(layer "F.Fab")
			(effects
				(font
					(size 1.27 1.27)
				)
			)
		)
		(duplicate_pad_numbers_are_jumpers no)
		(fp_line
			(start -1.7272 1.1176)
			(end -1.7272 -1.1176)
			(stroke
				(width 0.1524)
				(type default)
			)
			(layer "F.SilkS")
		)
		(fp_line
			(start -0.254 -1.1176)
			(end -1.7272 -1.1176)
			(stroke
				(width 0.1524)
				(type default)
			)
			(layer "F.SilkS")
		)
		(fp_line
			(start 0 -0.7366)
			(end -0.254 -1.1176)
			(stroke
				(width 0.1524)
				(type default)
			)
			(layer "F.SilkS")
		)
		(fp_line
			(start 0.254 -1.1176)
			(end 0 -0.7366)
			(stroke
				(width 0.1524)
				(type default)
			)
			(layer "F.SilkS")
		)
		(fp_line
			(start 1.7272 -1.1176)
			(end 0.254 -1.1176)
			(stroke
				(width 0.1524)
				(type default)
			)
			(layer "F.SilkS")
		)
		(fp_line
			(start 1.7272 -1.1176)
			(end 1.7272 1.1176)
			(stroke
				(width 0.1524)
				(type default)
			)
			(layer "F.SilkS")
		)
		(fp_line
			(start 1.7272 1.1176)
			(end -1.7272 1.1176)
			(stroke
				(width 0.1524)
				(type default)
			)
			(layer "F.SilkS")
		)
		(fp_poly
			(pts
				(xy -2.7178 -0.268986) (xy -2.7178 -1.030986) (xy -1.9558 -0.649986)
			)
			(stroke
				(width 0)
				(type default)
			)
			(fill yes)
			(layer "F.SilkS")
		)
		(fp_line
			(start -1.5748 -1.1176)
			(end -1.5748 1.1176)
			(stroke
				(width 0.1)
				(type default)
			)
			(layer "F.Fab")
		)
		(fp_line
			(start -1.5748 1.1176)
			(end 1.5748 1.1176)
			(stroke
				(width 0.1)
				(type default)
			)
			(layer "F.Fab")
		)
		(fp_line
			(start 1.5748 -1.1176)
			(end -1.5748 -1.1176)
			(stroke
				(width 0.1)
				(type default)
			)
			(layer "F.Fab")
		)
		(fp_line
			(start 1.5748 1.1176)
			(end 1.5748 -1.1176)
			(stroke
				(width 0.1)
				(type default)
			)
			(layer "F.Fab")
		)
		(fp_poly
			(pts
				(xy -1.9558 -0.649986) (xy -2.7178 -0.268986) (xy -2.7178 -1.030986)
			)
			(stroke
				(width 0)
				(type default)
			)
			(fill yes)
			(layer "F.Fab")
		)
		(pad "1" smd rect
			(at -0.999998 -0.649986 270)
			(size 0.3556 1.1176)
			(layers "F.Cu" "F.Mask" "F.Paste")
			(net "OCP_V3_2_NOT_PRSNT_RBT_ARB_IN")
		)
		(pad "2" smd rect
			(at -0.999998 0 270)
			(size 0.3556 1.1176)
			(layers "F.Cu" "F.Mask" "F.Paste")
			(net "GND")
		)
		(pad "3" smd rect
			(at -0.999998 0.649986 270)
			(size 0.3556 1.1176)
			(layers "F.Cu" "F.Mask" "F.Paste")
			(net "OCP_V3_2_RBT_ARB_OUT")
		)
		(pad "4" smd rect
			(at 0.999998 0.649986 270)
			(size 0.3556 1.1176)
			(layers "F.Cu" "F.Mask" "F.Paste")
			(net "OCP_SFF_RBT_ARB_IN_MUX1")
		)
		(pad "5" smd rect
			(at 0.999998 0 270)
			(size 0.3556 1.1176)
			(layers "F.Cu" "F.Mask" "F.Paste")
			(net "P3V3_AUX")
		)
		(pad "6" smd rect
			(at 0.999998 -0.649986 270)
			(size 0.3556 1.1176)
			(layers "F.Cu" "F.Mask" "F.Paste")
			(net "OCP_V3_2_PRSNT_ALL_R1_N")
		)
	)
)
